# BASEBOARD_FAB2 (Tioga Pass) — schematic netlist excerpt (pin names and nets, part order shuffled) for the footprints in the layout excerpt that follows; sources: Cadence DE-HDL packaged netlist, KiCad conversion of Wiwynn_Tioga_Pass_MB.brd

C2B1  CAP_A  47UF 4V 20% X5R  pkg 0603V  page 228 : A = PVDDQ_KLM ; B = GND
R1G9  RES  0.0 5% CHIP  pkg 0402  page 223 : A = SVID_ALERT_PVDDQ_GHJ ; B = SVID_ALERT1_CPU1_R_N

(kicad_pcb
	(version 20260206)
	(generator "pcbnew")
	(generator_version "10.0")
	(general
		(thickness 1.6)
		(legacy_teardrops no)
	)
	(paper "A4")
	(title_block
		(title "Wiwynn_Tioga_Pass_MB.brd")
		(comment 1 "Tioga Pass / footprints 2081-2082 of 4770")
	)
	(layers
		(0 "F.Cu" signal "TOP")
		(4 "In1.Cu" signal "L2GND")
		(6 "In2.Cu" signal "L3")
		(8 "In3.Cu" signal "L4GND")
		(10 "In4.Cu" signal "L5")
		(12 "In5.Cu" signal "L6GND")
		(14 "In6.Cu" signal "L7VCC")
		(16 "In7.Cu" signal "L8VCC")
		(18 "In8.Cu" signal "L9GND")
		(20 "In9.Cu" signal "L10")
		(22 "In10.Cu" signal "L11GND")
		(24 "In11.Cu" signal "L12")
		(26 "In12.Cu" signal "L13GND")
		(2 "B.Cu" signal "BOTTOM")
		(9 "F.Adhes" user "F.Adhesive")
		(11 "B.Adhes" user "B.Adhesive")
		(13 "F.Paste" user "Package Geometry/Pastemask Top")
		(15 "B.Paste" user "Package Geometry/Pastemask Bottom")
		(5 "F.SilkS" user "Ref Des/Silkscreen Top")
		(7 "B.SilkS" user "Ref Des/Silkscreen Bottom")
		(1 "F.Mask" user "Board Geometry/Soldermask Top")
		(3 "B.Mask" user "Board Geometry/Soldermask Bottom")
		(17 "Dwgs.User" user "User.Drawings")
		(19 "Cmts.User" user "User.Comments")
		(21 "Eco1.User" user "User.Eco1")
		(23 "Eco2.User" user "User.Eco2")
		(25 "Edge.Cuts" user "Board Geometry/Outline")
		(27 "Margin" user)
		(31 "F.CrtYd" user "Package Geometry/Place Bound Top")
		(29 "B.CrtYd" user "Package Geometry/Place Bound Bottom")
		(35 "F.Fab" user "Ref Des/Assembly Top")
		(33 "B.Fab" user "Ref Des/Assembly Bottom")
	)
	(footprint ""
		(layer "F.Cu")
		(at 9.585706 -3.355848 180)
		(property "Reference" "R1G9"
			(at 0 0 180)
			(layer "F.SilkS")
			(hide yes)
			(effects
				(font
					(size 1.27 1.27)
				)
			)
		)
		(property "Value" ""
			(at 0 0 180)
			(layer "F.Fab")
			(effects
				(font
					(size 1.27 1.27)
				)
			)
		)
		(duplicate_pad_numbers_are_jumpers no)
		(fp_rect
			(start 0.2794 0.9906)
			(end -0.2794 -0.1016)
			(stroke
				(width 0)
				(type default)
			)
			(fill no)
			(layer "F.CrtYd")
		)
		(fp_line
			(start 0.2794 0.9906)
			(end 0.2794 -0.1016)
			(stroke
				(width 0.1)
				(type default)
			)
			(layer "F.Fab")
		)
		(fp_line
			(start 0.2794 -0.1016)
			(end -0.2794 -0.1016)
			(stroke
				(width 0.1)
				(type default)
			)
			(layer "F.Fab")
		)
		(fp_line
			(start -0.2794 0.9906)
			(end 0.2794 0.9906)
			(stroke
				(width 0.1)
				(type default)
			)
			(layer "F.Fab")
		)
		(fp_line
			(start -0.2794 -0.1016)
			(end -0.2794 0.9906)
			(stroke
				(width 0.1)
				(type default)
			)
			(layer "F.Fab")
		)
		(pad "1" smd rect
			(at 0 0 180)
			(size 0.508 0.508)
			(layers "F.Cu" "F.Mask" "F.Paste")
			(net "SVID_ALERT_PVDDQ_GHJ")
		)
		(pad "2" smd rect
			(at 0 0.889 180)
			(size 0.508 0.508)
			(layers "F.Cu" "F.Mask" "F.Paste")
			(net "SVID_ALERT1_CPU1_R_N")
		)
		(zone
			(layer "F.Cu")
			(hatch none 0.5)
			(connect_pads
				(clearance 0)
			)
			(min_thickness 0.25)
			(keepout
				(tracks allowed)
				(vias not_allowed)
				(pads allowed)
				(copperpour not_allowed)
				(footprints allowed)
			)
			(placement
				(enabled no)
				(sheetname "")
			)
			(fill
				(thermal_gap 0.5)
				(thermal_bridge_width 0.5)
				(island_removal_mode 0)
			)
			(polygon
				(pts
					(xy 9.331706 -3.990848) (xy 9.331706 -3.609848) (xy 9.839706 -3.609848) (xy 9.839706 -3.990848)
				)
			)
		)
		(zone
			(layer "F.Cu")
			(hatch none 0.5)
			(connect_pads
				(clearance 0)
			)
			(min_thickness 0.25)
			(keepout
				(tracks not_allowed)
				(vias allowed)
				(pads allowed)
				(copperpour not_allowed)
				(footprints allowed)
			)
			(placement
				(enabled no)
				(sheetname "")
			)
			(fill
				(thermal_gap 0.5)
				(thermal_bridge_width 0.5)
				(island_removal_mode 0)
			)
			(polygon
				(pts
					(xy 9.331706 -3.990848) (xy 9.331706 -3.609848) (xy 9.839706 -3.609848) (xy 9.839706 -3.990848)
				)
			)
		)
	)
	(footprint ""
		(layer "F.Cu")
		(at 96.746568 -129.859024)
		(property "Reference" "C2B1"
			(at 0 0 0)
			(layer "F.SilkS")
			(hide yes)
			(effects
				(font
					(size 1.27 1.27)
				)
			)
		)
		(property "Value" ""
			(at 0 0 0)
			(layer "F.Fab")
			(effects
				(font
					(size 1.27 1.27)
				)
			)
		)
		(duplicate_pad_numbers_are_jumpers no)
		(fp_rect
			(start -0.500126 1.598422)
			(end 0.500126 -0.201422)
			(stroke
				(width 0)
				(type default)
			)
			(fill no)
			(layer "F.CrtYd")
		)
		(fp_line
			(start -0.500126 -0.201422)
			(end 0.500126 -0.201422)
			(stroke
				(width 0.1)
				(type default)
			)
			(layer "F.Fab")
		)
		(fp_line
			(start -0.500126 1.598422)
			(end -0.500126 -0.201422)
			(stroke
				(width 0.1)
				(type default)
			)
			(layer "F.Fab")
		)
		(fp_line
			(start 0.500126 -0.201422)
			(end 0.500126 1.598422)
			(stroke
				(width 0.1)
				(type default)
			)
			(layer "F.Fab")
		)
		(fp_line
			(start 0.500126 1.598422)
			(end -0.500126 1.598422)
			(stroke
				(width 0.1)
				(type default)
			)
			(layer "F.Fab")
		)
		(pad "1" smd rect
			(at 0 0 270)
			(size 0.889 0.9906)
			(layers "F.Cu" "F.Mask" "F.Paste")
			(net "PVDDQ_KLM")
		)
		(pad "2" smd rect
			(at 0 1.397 270)
			(size 0.889 0.9906)
			(layers "F.Cu" "F.Mask" "F.Paste")
			(net "GND")
		)
		(zone
			(layer "F.Cu")
			(hatch none 0.5)
			(connect_pads
				(clearance 0)
			)
			(min_thickness 0.25)
			(keepout
				(tracks allowed)
				(vias not_allowed)
				(pads allowed)
				(copperpour not_allowed)
				(footprints allowed)
			)
			(placement
				(enabled no)
				(sheetname "")
			)
			(fill
				(thermal_gap 0.5)
				(thermal_bridge_width 0.5)
				(island_removal_mode 0)
			)
			(polygon
				(pts
					(xy 96.251268 -128.906524) (xy 97.241868 -128.906524) (xy 97.241868 -129.414524) (xy 96.251268 -129.414524)
				)
			)
		)
		(zone
			(layer "F.Cu")
			(hatch none 0.5)
			(connect_pads
				(clearance 0)
			)
			(min_thickness 0.25)
			(keepout
				(tracks not_allowed)
				(vias allowed)
				(pads allowed)
				(copperpour not_allowed)
				(footprints allowed)
			)
			(placement
				(enabled no)
				(sheetname "")
			)
			(fill
				(thermal_gap 0.5)
				(thermal_bridge_width 0.5)
				(island_removal_mode 0)
			)
			(polygon
				(pts
					(xy 96.251268 -128.906524) (xy 97.241868 -128.906524) (xy 97.241868 -129.414524) (xy 96.251268 -129.414524)
				)
			)
		)
	)
)
